(kicad_pcb
	(version 20260206)
	(generator "pcbnew")
	(generator_version "10.0")
	(general
		(thickness 1.6)
		(legacy_teardrops no)
	)
	(paper "A4")
	(title_block
		(title "Wiwynn_Tioga_Pass_MB.brd")
		(comment 1 "Tioga Pass / footprints 1502-1508 of 4770")
	)
	(layers
		(0 "F.Cu" signal "TOP")
		(4 "In1.Cu" signal "L2GND")
		(6 "In2.Cu" signal "L3")
		(8 "In3.Cu" signal "L4GND")
		(10 "In4.Cu" signal "L5")
		(12 "In5.Cu" signal "L6GND")
		(14 "In6.Cu" signal "L7VCC")
		(16 "In7.Cu" signal "L8VCC")
		(18 "In8.Cu" signal "L9GND")
		(20 "In9.Cu" signal "L10")
		(22 "In10.Cu" signal "L11GND")
		(24 "In11.Cu" signal "L12")
		(26 "In12.Cu" signal "L13GND")
		(2 "B.Cu" signal "BOTTOM")
		(9 "F.Adhes" user "F.Adhesive")
		(11 "B.Adhes" user "B.Adhesive")
		(13 "F.Paste" user "Package Geometry/Pastemask Top")
		(15 "B.Paste" user "Package Geometry/Pastemask Bottom")
		(5 "F.SilkS" user "Ref Des/Silkscreen Top")
		(7 "B.SilkS" user "Ref Des/Silkscreen Bottom")
		(1 "F.Mask" user "Board Geometry/Soldermask Top")
		(3 "B.Mask" user "Board Geometry/Soldermask Bottom")
		(17 "Dwgs.User" user "User.Drawings")
		(19 "Cmts.User" user "User.Comments")
		(21 "Eco1.User" user "User.Eco1")
		(23 "Eco2.User" user "User.Eco2")
		(25 "Edge.Cuts" user "Board Geometry/Outline")
		(27 "Margin" user)
		(31 "F.CrtYd" user "Package Geometry/Place Bound Top")
		(29 "B.CrtYd" user "Package Geometry/Place Bound Bottom")
		(35 "F.Fab" user "Ref Des/Assembly Top")
		(33 "B.Fab" user "Ref Des/Assembly Bottom")
	)
	(footprint ""
		(layer "F.Cu")
		(at 383.660904 -76.026264 180)
		(property "Reference" "R2T37"
			(at 0 0 180)
			(layer "F.SilkS")
			(hide yes)
			(effects
				(font
					(size 1.27 1.27)
				)
			)
		)
		(property "Value" ""
			(at 0 0 180)
			(layer "F.Fab")
			(effects
				(font
					(size 1.27 1.27)
				)
			)
		)
		(duplicate_pad_numbers_are_jumpers no)
		(fp_poly
			(pts
				(xy -0.2794 -0.1016) (xy 0.2794 -0.1016) (xy 0.2794 0.9906) (xy -0.2794 0.9906)
			)
			(stroke
				(width 0)
				(type default)
			)
			(fill no)
			(layer "F.CrtYd")
		)
		(fp_line
			(start 0.2794 0.9906)
			(end 0.2794 -0.1016)
			(stroke
				(width 0.1)
				(type default)
			)
			(layer "F.Fab")
		)
		(fp_line
			(start 0.2794 -0.1016)
			(end -0.2794 -0.1016)
			(stroke
				(width 0.1)
				(type default)
			)
			(layer "F.Fab")
		)
		(fp_line
			(start -0.2794 0.9906)
			(end 0.2794 0.9906)
			(stroke
				(width 0.1)
				(type default)
			)
			(layer "F.Fab")
		)
		(fp_line
			(start -0.2794 -0.1016)
			(end -0.2794 0.9906)
			(stroke
				(width 0.1)
				(type default)
			)
			(layer "F.Fab")
		)
		(pad "1" smd rect
			(at 0 0 180)
			(size 0.508 0.508)
			(layers "F.Cu" "F.Mask" "F.Paste")
			(net "PVCCIO_CPU0")
		)
		(pad "2" smd rect
			(at 0 0.889 180)
			(size 0.508 0.508)
			(layers "F.Cu" "F.Mask" "F.Paste")
			(net "H_CPU_ERR2_G_R_N")
		)
		(zone
			(layer "F.Cu")
			(hatch none 0.5)
			(connect_pads
				(clearance 0)
			)
			(min_thickness 0.25)
			(keepout
				(tracks not_allowed)
				(vias allowed)
				(pads allowed)
				(copperpour not_allowed)
				(footprints allowed)
			)
			(placement
				(enabled no)
				(sheetname "")
			)
			(fill
				(thermal_gap 0.5)
				(thermal_bridge_width 0.5)
				(island_removal_mode 0)
			)
			(polygon
				(pts
					(xy 383.914904 -76.661264) (xy 383.406904 -76.661264) (xy 383.406904 -76.280264) (xy 383.914904 -76.280264)
				)
			)
		)
		(zone
			(layer "F.Cu")
			(hatch none 0.5)
			(connect_pads
				(clearance 0)
			)
			(min_thickness 0.25)
			(keepout
				(tracks allowed)
				(vias not_allowed)
				(pads allowed)
				(copperpour not_allowed)
				(footprints allowed)
			)
			(placement
				(enabled no)
				(sheetname "")
			)
			(fill
				(thermal_gap 0.5)
				(thermal_bridge_width 0.5)
				(island_removal_mode 0)
			)
			(polygon
				(pts
					(xy 383.914904 -76.280264) (xy 383.406904 -76.280264) (xy 383.406904 -76.661264) (xy 383.914904 -76.661264)
				)
			)
		)
	)
	(footprint ""
		(layer "F.Cu")
		(at 274.447 -69.977)
		(property "Reference" "R5D3"
			(at 0 0 0)
			(layer "F.SilkS")
			(hide yes)
			(effects
				(font
					(size 1.27 1.27)
				)
			)
		)
		(property "Value" ""
			(at 0 0 0)
			(layer "F.Fab")
			(effects
				(font
					(size 1.27 1.27)
				)
			)
		)
		(duplicate_pad_numbers_are_jumpers no)
		(fp_poly
			(pts
				(xy -0.2794 -0.1016) (xy 0.2794 -0.1016) (xy 0.2794 0.9906) (xy -0.2794 0.9906)
			)
			(stroke
				(width 0)
				(type default)
			)
			(fill no)
			(layer "F.CrtYd")
		)
		(fp_line
			(start -0.2794 -0.1016)
			(end -0.2794 0.9906)
			(stroke
				(width 0.1)
				(type default)
			)
			(layer "F.Fab")
		)
		(fp_line
			(start -0.2794 0.9906)
			(end 0.2794 0.9906)
			(stroke
				(width 0.1)
				(type default)
			)
			(layer "F.Fab")
		)
		(fp_line
			(start 0.2794 -0.1016)
			(end -0.2794 -0.1016)
			(stroke
				(width 0.1)
				(type default)
			)
			(layer "F.Fab")
		)
		(fp_line
			(start 0.2794 0.9906)
			(end 0.2794 -0.1016)
			(stroke
				(width 0.1)
				(type default)
			)
			(layer "F.Fab")
		)
		(pad "1" smd rect
			(at 0 0)
			(size 0.508 0.508)
			(layers "F.Cu" "F.Mask" "F.Paste")
			(net "PVCCIO_CPU0")
		)
		(pad "2" smd rect
			(at 0 0.889)
			(size 0.508 0.508)
			(layers "F.Cu" "F.Mask" "F.Paste")
			(net "PU_CPU0_FRMAGENT")
		)
		(zone
			(layer "F.Cu")
			(hatch none 0.5)
			(connect_pads
				(clearance 0)
			)
			(min_thickness 0.25)
			(keepout
				(tracks allowed)
				(vias not_allowed)
				(pads allowed)
				(copperpour not_allowed)
				(footprints allowed)
			)
			(placement
				(enabled no)
				(sheetname "")
			)
			(fill
				(thermal_gap 0.5)
				(thermal_bridge_width 0.5)
				(island_removal_mode 0)
			)
			(polygon
				(pts
					(xy 274.193 -69.723) (xy 274.701 -69.723) (xy 274.701 -69.342) (xy 274.193 -69.342)
				)
			)
		)
		(zone
			(layer "F.Cu")
			(hatch none 0.5)
			(connect_pads
				(clearance 0)
			)
			(min_thickness 0.25)
			(keepout
				(tracks not_allowed)
				(vias allowed)
				(pads allowed)
				(copperpour not_allowed)
				(footprints allowed)
			)
			(placement
				(enabled no)
				(sheetname "")
			)
			(fill
				(thermal_gap 0.5)
				(thermal_bridge_width 0.5)
				(island_removal_mode 0)
			)
			(polygon
				(pts
					(xy 274.193 -69.342) (xy 274.701 -69.342) (xy 274.701 -69.723) (xy 274.193 -69.723)
				)
			)
		)
	)
	(footprint ""
		(layer "F.Cu")
		(at 174.4218 -6.2103 180)
		(property "Reference" "R4G25"
			(at 0 0 180)
			(layer "F.SilkS")
			(hide yes)
			(effects
				(font
					(size 1.27 1.27)
				)
			)
		)
		(property "Value" ""
			(at 0 0 180)
			(layer "F.Fab")
			(effects
				(font
					(size 1.27 1.27)
				)
			)
		)
		(duplicate_pad_numbers_are_jumpers no)
		(fp_rect
			(start 0.2794 -0.1016)
			(end -0.2794 0.9906)
			(stroke
				(width 0)
				(type default)
			)
			(fill no)
			(layer "F.CrtYd")
		)
		(fp_line
			(start 0.2794 0.9906)
			(end 0.2794 -0.1016)
			(stroke
				(width 0.1)
				(type default)
			)
			(layer "F.Fab")
		)
		(fp_line
			(start 0.2794 -0.1016)
			(end -0.2794 -0.1016)
			(stroke
				(width 0.1)
				(type default)
			)
			(layer "F.Fab")
		)
		(fp_line
			(start -0.2794 0.9906)
			(end 0.2794 0.9906)
			(stroke
				(width 0.1)
				(type default)
			)
			(layer "F.Fab")
		)
		(fp_line
			(start -0.2794 -0.1016)
			(end -0.2794 0.9906)
			(stroke
				(width 0.1)
				(type default)
			)
			(layer "F.Fab")
		)
		(pad "1" smd rect
			(at 0 0 180)
			(size 0.508 0.508)
			(layers "F.Cu" "F.Mask" "F.Paste")
			(net "GND")
		)
		(pad "2" smd rect
			(at 0 0.889 180)
			(size 0.508 0.508)
			(layers "F.Cu" "F.Mask" "F.Paste")
			(net "AGND_PVPP_GHJ")
		)
		(zone
			(layer "F.Cu")
			(hatch none 0.5)
			(connect_pads
				(clearance 0)
			)
			(min_thickness 0.25)
			(keepout
				(tracks allowed)
				(vias not_allowed)
				(pads allowed)
				(copperpour not_allowed)
				(footprints allowed)
			)
			(placement
				(enabled no)
				(sheetname "")
			)
			(fill
				(thermal_gap 0.5)
				(thermal_bridge_width 0.5)
				(island_removal_mode 0)
			)
			(polygon
				(pts
					(xy 174.1678 -6.4643) (xy 174.6758 -6.4643) (xy 174.6758 -6.8453) (xy 174.1678 -6.8453)
				)
			)
		)
		(zone
			(layer "F.Cu")
			(hatch none 0.5)
			(connect_pads
				(clearance 0)
			)
			(min_thickness 0.25)
			(keepout
				(tracks not_allowed)
				(vias allowed)
				(pads allowed)
				(copperpour not_allowed)
				(footprints allowed)
			)
			(placement
				(enabled no)
				(sheetname "")
			)
			(fill
				(thermal_gap 0.5)
				(thermal_bridge_width 0.5)
				(island_removal_mode 0)
			)
			(polygon
				(pts
					(xy 174.1678 -6.4643) (xy 174.6758 -6.4643) (xy 174.6758 -6.8453) (xy 174.1678 -6.8453)
				)
			)
		)
	)
	(footprint ""
		(layer "F.Cu")
		(at 451.85838 -32.4485 90)
		(property "Reference" "R25W52"
			(at 0 0 90)
			(layer "F.SilkS")
			(hide yes)
			(effects
				(font
					(size 1.27 1.27)
				)
			)
		)
		(property "Value" "*"
			(at 0.064008 -4.108196 90)
			(unlocked yes)
			(layer "F.Fab")
			(hide yes)
			(effects
				(font
					(size 1.27 1.016)
					(thickness 0.1524)
				)
			)
		)
		(property "Device Type" "120R2F-GP_RCL_GP-120R2F-GP,64.A"
			(at 0.064008 -5.632196 90)
			(unlocked yes)
			(layer "F.Fab")
			(hide yes)
			(effects
				(font
					(size 1.27 1.016)
					(thickness 0.1524)
				)
			)
		)
		(duplicate_pad_numbers_are_jumpers no)
		(fp_line
			(start 0.508 -0.9398)
			(end -0.508 -0.9398)
			(stroke
				(width 0.1524)
				(type default)
			)
			(layer "F.SilkS")
		)
		(fp_line
			(start -0.508 -0.9398)
			(end -0.508 0.9398)
			(stroke
				(width 0.1524)
				(type default)
			)
			(layer "F.SilkS")
		)
		(fp_rect
			(start -0.508 0.9398)
			(end 0.508 -0.9398)
			(stroke
				(width 0)
				(type default)
			)
			(fill no)
			(layer "F.CrtYd")
		)
		(fp_rect
			(start -0.508 0.9398)
			(end 0.508 -0.9398)
			(stroke
				(width 0)
				(type default)
			)
			(fill no)
			(layer "F.Fab")
		)
		(pad "1" smd custom
			(at 0 -0.4445 90)
			(size 0.1397 0.1397)
			(layers "F.Cu" "F.Mask" "F.Paste")
			(net "BMC_M_MACT_N")
			(options
				(clearance outline)
				(anchor circle)
			)
			(primitives
				(gr_poly
					(pts
						(arc
							(start -0.1778 -0.2794)
							(mid -0.249642 -0.249642)
							(end -0.2794 -0.1778)
						)
						(arc
							(start -0.2794 0.1778)
							(mid -0.249642 0.249642)
							(end -0.1778 0.2794)
						)
						(arc
							(start 0.1778 0.2794)
							(mid 0.249642 0.249642)
							(end 0.2794 0.1778)
						)
						(arc
							(start 0.2794 -0.1778)
							(mid 0.249642 -0.249642)
							(end 0.1778 -0.2794)
						)
					)
					(width 0)
					(fill yes)
				)
			)
		)
		(pad "2" smd custom
			(at 0 0.4445 90)
			(size 0.1397 0.1397)
			(layers "F.Cu" "F.Mask" "F.Paste")
			(net "P1V2_AUX_BMC")
			(options
				(clearance outline)
				(anchor circle)
			)
			(primitives
				(gr_poly
					(pts
						(arc
							(start -0.1778 -0.2794)
							(mid -0.249642 -0.249642)
							(end -0.2794 -0.1778)
						)
						(arc
							(start -0.2794 0.1778)
							(mid -0.249642 0.249642)
							(end -0.1778 0.2794)
						)
						(arc
							(start 0.1778 0.2794)
							(mid 0.249642 0.249642)
							(end 0.2794 0.1778)
						)
						(arc
							(start 0.2794 -0.1778)
							(mid 0.249642 -0.249642)
							(end 0.1778 -0.2794)
						)
					)
					(width 0)
					(fill yes)
				)
			)
		)
	)
	(footprint ""
		(layer "F.Cu")
		(at 369.954556 -156.250894 180)
		(property "Reference" "C7A14"
			(at 0 0 180)
			(layer "F.SilkS")
			(hide yes)
			(effects
				(font
					(size 1.27 1.27)
				)
			)
		)
		(property "Value" "*"
			(at -0.0762 -6.2357 180)
			(unlocked yes)
			(layer "F.Fab")
			(hide yes)
			(effects
				(font
					(size 1.27 1.016)
					(thickness 0.1524)
				)
			)
		)
		(property "Device Type" "SC22U16V5MX-4-GP_SMD-BCG5-SC22A"
			(at -0.0762 -8.2677 180)
			(unlocked yes)
			(layer "F.Fab")
			(hide yes)
			(effects
				(font
					(size 1.27 1.016)
					(thickness 0.1524)
				)
			)
		)
		(duplicate_pad_numbers_are_jumpers no)
		(fp_line
			(start 0.635 0)
			(end -0.635 0)
			(stroke
				(width 0.508)
				(type default)
			)
			(layer "F.SilkS")
		)
		(fp_rect
			(start -0.9652 1.778)
			(end 0.9652 -1.778)
			(stroke
				(width 0)
				(type default)
			)
			(fill no)
			(layer "F.CrtYd")
		)
		(fp_poly
			(pts
				(xy -0.9652 -1.778) (xy 0.9652 -1.778) (xy 0.9652 1.778) (xy -0.9652 1.778)
			)
			(stroke
				(width 0)
				(type default)
			)
			(fill no)
			(layer "F.Fab")
		)
		(pad "1" smd rect
			(at 0 -0.9652 180)
			(size 1.397 1.143)
			(layers "F.Cu" "F.Mask" "F.Paste")
			(net "VR_FET_SW_P12V_STBY_PVDDQ_DEF")
		)
		(pad "2" smd rect
			(at 0 0.9652 180)
			(size 1.397 1.143)
			(layers "F.Cu" "F.Mask" "F.Paste")
			(net "GND")
		)
	)
	(footprint ""
		(layer "F.Cu")
		(at 320.296032 -140.208 90)
		(property "Reference" "C6A7"
			(at 0 0 90)
			(layer "F.SilkS")
			(hide yes)
			(effects
				(font
					(size 1.27 1.27)
				)
			)
		)
		(property "Value" ""
			(at 0 0 90)
			(layer "F.Fab")
			(effects
				(font
					(size 1.27 1.27)
				)
			)
		)
		(duplicate_pad_numbers_are_jumpers no)
		(fp_poly
			(pts
				(xy -0.4953 -0.2032) (xy 0.4953 -0.2032) (xy 0.4953 1.6002) (xy -0.4953 1.6002)
			)
			(stroke
				(width 0)
				(type default)
			)
			(fill no)
			(layer "F.CrtYd")
		)
		(fp_line
			(start 0.4953 -0.2032)
			(end 0.4953 1.6002)
			(stroke
				(width 0.1)
				(type default)
			)
			(layer "F.Fab")
		)
		(fp_line
			(start -0.4953 -0.2032)
			(end 0.4953 -0.2032)
			(stroke
				(width 0.1)
				(type default)
			)
			(layer "F.Fab")
		)
		(fp_line
			(start 0.4953 1.6002)
			(end -0.4953 1.6002)
			(stroke
				(width 0.1)
				(type default)
			)
			(layer "F.Fab")
		)
		(fp_line
			(start -0.4953 1.6002)
			(end -0.4953 -0.2032)
			(stroke
				(width 0.1)
				(type default)
			)
			(layer "F.Fab")
		)
		(pad "1" smd rect
			(at 0 0 90)
			(size 0.762 0.889)
			(layers "F.Cu" "F.Mask" "F.Paste")
			(net "PVPP_DEF")
		)
		(pad "2" smd rect
			(at 0 1.397 90)
			(size 0.762 0.889)
			(layers "F.Cu" "F.Mask" "F.Paste")
			(net "GND")
		)
		(zone
			(layer "F.Cu")
			(hatch none 0.5)
			(connect_pads
				(clearance 0)
			)
			(min_thickness 0.25)
			(keepout
				(tracks not_allowed)
				(vias allowed)
				(pads allowed)
				(copperpour not_allowed)
				(footprints allowed)
			)
			(placement
				(enabled no)
				(sheetname "")
			)
			(fill
				(thermal_gap 0.5)
				(thermal_bridge_width 0.5)
				(island_removal_mode 0)
			)
			(polygon
				(pts
					(xy 320.740532 -139.827) (xy 320.740532 -140.589) (xy 321.248532 -140.589) (xy 321.248532 -139.827)
				)
			)
		)
	)
	(footprint ""
		(layer "F.Cu")
		(at 332.888844 -117.35562 90)
		(property "Reference" "C6B20"
			(at -0.8382 -0.67818 90)
			(unlocked yes)
			(layer "F.SilkS")
			(effects
				(font
					(size 0.4064 0.254)
					(thickness 0.1524)
				)
				(justify left)
			)
		)
		(property "Value" ""
			(at 0 0 90)
			(layer "F.Fab")
			(effects
				(font
					(size 1.27 1.27)
				)
			)
		)
		(duplicate_pad_numbers_are_jumpers no)
		(fp_poly
			(pts
				(xy 0.3048 -0.1016) (xy 0.3048 0.9906) (xy -0.3048 0.9906) (xy -0.3048 -0.1016)
			)
			(stroke
				(width 0)
				(type default)
			)
			(fill no)
			(layer "F.CrtYd")
		)
		(fp_line
			(start 0.3048 -0.1016)
			(end -0.3048 -0.1016)
			(stroke
				(width 0.1)
				(type default)
			)
			(layer "F.Fab")
		)
		(fp_line
			(start -0.3048 -0.1016)
			(end -0.3048 0.9906)
			(stroke
				(width 0.1)
				(type default)
			)
			(layer "F.Fab")
		)
		(fp_line
			(start 0.3048 0.9906)
			(end 0.3048 -0.1016)
			(stroke
				(width 0.1)
				(type default)
			)
			(layer "F.Fab")
		)
		(fp_line
			(start -0.3048 0.9906)
			(end 0.3048 0.9906)
			(stroke
				(width 0.1)
				(type default)
			)
			(layer "F.Fab")
		)
		(pad "1" smd rect
			(at 0 0 90)
			(size 0.508 0.508)
			(layers "F.Cu" "F.Mask" "F.Paste")
			(net "P3E_CPU0_PE1_PCH_TXP<8>")
		)
		(pad "2" smd rect
			(at 0 0.889 90)
			(size 0.508 0.508)
			(layers "F.Cu" "F.Mask" "F.Paste")
			(net "P3E_CPU0_PE1_PCH_C_TXP<8>")
		)
		(zone
			(layer "F.Cu")
			(hatch none 0.5)
			(connect_pads
				(clearance 0)
			)
			(min_thickness 0.25)
			(keepout
				(tracks allowed)
				(vias not_allowed)
				(pads allowed)
				(copperpour not_allowed)
				(footprints allowed)
			)
			(placement
				(enabled no)
				(sheetname "")
			)
			(fill
				(thermal_gap 0.5)
				(thermal_bridge_width 0.5)
				(island_removal_mode 0)
			)
			(polygon
				(pts
					(xy 333.142844 -117.10162) (xy 333.142844 -117.60962) (xy 333.523844 -117.60962) (xy 333.523844 -117.10162)
				)
			)
		)
		(zone
			(layer "F.Cu")
			(hatch none 0.5)
			(connect_pads
				(clearance 0)
			)
			(min_thickness 0.25)
			(keepout
				(tracks not_allowed)
				(vias allowed)
				(pads allowed)
				(copperpour not_allowed)
				(footprints allowed)
			)
			(placement
				(enabled no)
				(sheetname "")
			)
			(fill
				(thermal_gap 0.5)
				(thermal_bridge_width 0.5)
				(island_removal_mode 0)
			)
			(polygon
				(pts
					(xy 333.523844 -117.10162) (xy 333.523844 -117.60962) (xy 333.142844 -117.60962) (xy 333.142844 -117.10162)
				)
			)
		)
	)
)
